FILE_TYPE=LIBRARY_PARTS;
primitive 'SC4D7U10V3KX-GP_SMD-BCG';
  pin
    '1':
      PIN_NUMBER='(1)';
      PIN_TYPE='ANALOG';
      NO_LOAD_CHECK='Both';
      NO_IO_CHECK='Both';
      NO_ASSERT_CHECK='TRUE';
      NO_DIR_CHECK='TRUE';
      ALLOW_CONNECT='TRUE';
    '2':
      PIN_NUMBER='(2)';
      PIN_TYPE='ANALOG';
      NO_LOAD_CHECK='Both';
      NO_IO_CHECK='Both';
      NO_ASSERT_CHECK='TRUE';
      NO_DIR_CHECK='TRUE';
      ALLOW_CONNECT='TRUE';
  end_pin;
  body
    PART_NAME='SC4D7U10V3KX-GP';
    BODY_NAME='SC4D7U10V3KX-GP';
    PHYS_DES_PREFIX='C';
    CLASS='DISCRETE';
  end_body;
end_primitive;

END.
